# TIMECARD (Time Appliance Project (Time Card)) — schematic netlist excerpt (pin names and nets, part order shuffled) for the footprints in the layout excerpt that follows; sources: Cadence DE-HDL packaged netlist, KiCad conversion of R4006-B0001-02_R01.brd

R314  RESISTOR  4.7KOHM 1%  pkg SMC_0402R_H016  page 19 : \1\ = XP3R3V_FPGA ; \2\ = UNNAMED_8_PCA9508DPTSSOP8_I51_E
C315  CAPACITOR  0.1UF 25V 10%  pkg SMC_0402R_H022  page 26 : \1\ = XP3R3V_FPGA ; \2\ = SG

(kicad_pcb
	(version 20260206)
	(generator "pcbnew")
	(generator_version "10.0")
	(general
		(thickness 1.6)
		(legacy_teardrops no)
	)
	(paper "A4")
	(title_block
		(title "timecard-production-celestica-r4006 — R4006-B0001-02_R01.brd")
		(comment 1 "Time Appliance Project (Time Card) / footprints 738-739 of 1113")
	)
	(layers
		(0 "F.Cu" signal "TOP")
		(4 "In1.Cu" signal "L02_GND1")
		(6 "In2.Cu" signal "L03_SIG1")
		(8 "In3.Cu" signal "L04_GND2")
		(10 "In4.Cu" signal "L05_VCC1")
		(12 "In5.Cu" signal "L06_VCC2")
		(14 "In6.Cu" signal "L07_GND3")
		(16 "In7.Cu" signal "L08_SIG2")
		(18 "In8.Cu" signal "L09_GND4")
		(2 "B.Cu" signal "BOTTOM")
		(9 "F.Adhes" user "F.Adhesive")
		(11 "B.Adhes" user "B.Adhesive")
		(13 "F.Paste" user "Package Geometry/Pastemask Top")
		(15 "B.Paste" user "Package Geometry/Pastemask Bottom")
		(5 "F.SilkS" user "Ref Des/Silkscreen Top")
		(7 "B.SilkS" user "Ref Des/Silkscreen Bottom")
		(1 "F.Mask" user "Board Geometry/Soldermask Top")
		(3 "B.Mask" user "Board Geometry/Soldermask Bottom")
		(17 "Dwgs.User" user "User.Drawings")
		(19 "Cmts.User" user "User.Comments")
		(21 "Eco1.User" user "User.Eco1")
		(23 "Eco2.User" user "User.Eco2")
		(25 "Edge.Cuts" user "Board Geometry/Outline")
		(27 "Margin" user)
		(31 "F.CrtYd" user "Package Geometry/Place Bound Top")
		(29 "B.CrtYd" user "Package Geometry/Place Bound Bottom")
		(35 "F.Fab" user "Ref Des/Assembly Top")
		(33 "B.Fab" user "Ref Des/Assembly Bottom")
	)
	(footprint ""
		(layer "B.Cu")
		(at 111.125 -100.711 180)
		(property "Reference" "C315"
			(at -0.762 -1.30937 0)
			(unlocked yes)
			(layer "B.SilkS")
			(effects
				(font
					(size 0.7874 0.5842)
					(thickness 0.1524)
				)
				(justify mirror)
			)
		)
		(property "Value" "VAL*"
			(at -0.0762 2.067306 180)
			(unlocked yes)
			(layer "B.Fab")
			(hide yes)
			(effects
				(font
					(size 0.7874 0.5842)
					(thickness 0.1524)
				)
				(justify mirror)
			)
		)
		(property "Tolerance" "TOL*"
			(at -0.0762 3.032506 180)
			(unlocked yes)
			(layer "Cmts.User")
			(hide yes)
			(effects
				(font
					(size 0.7874 0.5842)
					(thickness 0.1524)
				)
				(justify mirror)
			)
		)
		(property "User Part Number" "PARTNUM*"
			(at -0.1016 4.023106 180)
			(unlocked yes)
			(layer "Cmts.User")
			(hide yes)
			(effects
				(font
					(size 0.7874 0.5842)
					(thickness 0.1524)
				)
				(justify mirror)
			)
		)
		(property "Device Type" "CAPACITOR-G105-0B104-EK,0.1UF,A"
			(at -0.0508 1.127506 180)
			(unlocked yes)
			(layer "B.Fab")
			(hide yes)
			(effects
				(font
					(size 0.7874 0.5842)
					(thickness 0.1524)
				)
				(justify mirror)
			)
		)
		(duplicate_pad_numbers_are_jumpers no)
		(fp_line
			(start 1.143 0.5588)
			(end -1.143 0.5588)
			(stroke
				(width 0.1)
				(type default)
			)
			(layer "B.SilkS")
		)
		(fp_line
			(start 1.143 -0.5588)
			(end 1.143 0.5588)
			(stroke
				(width 0.1)
				(type default)
			)
			(layer "B.SilkS")
		)
		(fp_line
			(start -1.143 0.5588)
			(end -1.143 -0.5588)
			(stroke
				(width 0.1)
				(type default)
			)
			(layer "B.SilkS")
		)
		(fp_line
			(start -1.143 -0.5588)
			(end 1.143 -0.5588)
			(stroke
				(width 0.1)
				(type default)
			)
			(layer "B.SilkS")
		)
		(fp_poly
			(pts
				(xy 1.143 0.5588) (xy -1.143 0.5588) (xy -1.143 -0.5588) (xy 1.143 -0.5588)
			)
			(stroke
				(width 0)
				(type default)
			)
			(fill no)
			(layer "B.CrtYd")
		)
		(fp_line
			(start 0.508 0.3048)
			(end -0.508 0.3048)
			(stroke
				(width 0.1)
				(type default)
			)
			(layer "B.Fab")
		)
		(fp_line
			(start 0.508 -0.3048)
			(end 0.508 0.3048)
			(stroke
				(width 0.1)
				(type default)
			)
			(layer "B.Fab")
		)
		(fp_line
			(start -0.508 0.3048)
			(end -0.508 -0.3048)
			(stroke
				(width 0.1)
				(type default)
			)
			(layer "B.Fab")
		)
		(fp_line
			(start -0.508 -0.3048)
			(end 0.508 -0.3048)
			(stroke
				(width 0.1)
				(type default)
			)
			(layer "B.Fab")
		)
		(pad "1" smd rect
			(at 0.5334 0)
			(size 0.7112 0.6096)
			(layers "B.Cu" "B.Mask" "B.Paste")
			(net "XP3R3V_FPGA")
		)
		(pad "2" smd rect
			(at -0.5334 0)
			(size 0.7112 0.6096)
			(layers "B.Cu" "B.Mask" "B.Paste")
			(net "SG")
		)
		(zone
			(layer "B.Cu")
			(hatch none 0.5)
			(connect_pads
				(clearance 0)
			)
			(min_thickness 0.25)
			(keepout
				(tracks not_allowed)
				(vias allowed)
				(pads allowed)
				(copperpour not_allowed)
				(footprints allowed)
			)
			(placement
				(enabled no)
				(sheetname "")
			)
			(fill
				(thermal_gap 0.5)
				(thermal_bridge_width 0.5)
				(island_removal_mode 0)
			)
			(polygon
				(pts
					(xy 111.0488 -101.0158) (xy 111.0488 -100.4062) (xy 111.2012 -100.4062) (xy 111.2012 -101.0158)
				)
			)
		)
		(zone
			(layer "B.Cu")
			(hatch none 0.5)
			(connect_pads
				(clearance 0)
			)
			(min_thickness 0.25)
			(keepout
				(tracks allowed)
				(vias not_allowed)
				(pads allowed)
				(copperpour not_allowed)
				(footprints allowed)
			)
			(placement
				(enabled no)
				(sheetname "")
			)
			(fill
				(thermal_gap 0.5)
				(thermal_bridge_width 0.5)
				(island_removal_mode 0)
			)
			(polygon
				(pts
					(xy 111.0488 -101.0158) (xy 111.0488 -100.4062) (xy 111.2012 -100.4062) (xy 111.2012 -101.0158)
				)
			)
		)
	)
	(footprint ""
		(layer "B.Cu")
		(at 22.7584 -61.5442 -90)
		(property "Reference" "R314"
			(at 3.1242 -0.69723 270)
			(unlocked yes)
			(layer "B.SilkS")
			(effects
				(font
					(size 0.7874 0.5842)
					(thickness 0.1524)
				)
				(justify mirror)
			)
		)
		(property "Value" "VAL*"
			(at -0.02032 2.13233 270)
			(unlocked yes)
			(layer "B.Fab")
			(hide yes)
			(effects
				(font
					(size 0.7874 0.5842)
					(thickness 0.1524)
				)
				(justify mirror)
			)
		)
		(property "Tolerance" "TOL*"
			(at -0.044704 3.05435 270)
			(unlocked yes)
			(layer "Cmts.User")
			(hide yes)
			(effects
				(font
					(size 0.7874 0.5842)
					(thickness 0.1524)
				)
				(justify mirror)
			)
		)
		(property "User Part Number" "PARTNUM*"
			(at -0.02032 4.024884 270)
			(unlocked yes)
			(layer "Cmts.User")
			(hide yes)
			(effects
				(font
					(size 0.7874 0.5842)
					(thickness 0.1524)
				)
				(justify mirror)
			)
		)
		(property "Device Type" "RESISTOR-G155-14701-01,4.7KOHMA"
			(at -0.008382 1.210564 270)
			(unlocked yes)
			(layer "B.Fab")
			(hide yes)
			(effects
				(font
					(size 0.7874 0.5842)
					(thickness 0.1524)
				)
				(justify mirror)
			)
		)
		(duplicate_pad_numbers_are_jumpers no)
		(fp_line
			(start -1.143 0.5588)
			(end -1.143 -0.5588)
			(stroke
				(width 0.1)
				(type default)
			)
			(layer "B.SilkS")
		)
		(fp_line
			(start 1.143 0.5588)
			(end -1.143 0.5588)
			(stroke
				(width 0.1)
				(type default)
			)
			(layer "B.SilkS")
		)
		(fp_line
			(start -1.143 -0.5588)
			(end 1.143 -0.5588)
			(stroke
				(width 0.1)
				(type default)
			)
			(layer "B.SilkS")
		)
		(fp_line
			(start 1.143 -0.5588)
			(end 1.143 0.5588)
			(stroke
				(width 0.1)
				(type default)
			)
			(layer "B.SilkS")
		)
		(fp_poly
			(pts
				(xy 1.143 0.5588) (xy -1.143 0.5588) (xy -1.143 -0.5588) (xy 1.143 -0.5588)
			)
			(stroke
				(width 0)
				(type default)
			)
			(fill no)
			(layer "B.CrtYd")
		)
		(fp_line
			(start -0.508 0.3048)
			(end -0.508 -0.3048)
			(stroke
				(width 0.1)
				(type default)
			)
			(layer "B.Fab")
		)
		(fp_line
			(start 0.508 0.3048)
			(end -0.508 0.3048)
			(stroke
				(width 0.1)
				(type default)
			)
			(layer "B.Fab")
		)
		(fp_line
			(start -0.508 -0.3048)
			(end 0.508 -0.3048)
			(stroke
				(width 0.1)
				(type default)
			)
			(layer "B.Fab")
		)
		(fp_line
			(start 0.508 -0.3048)
			(end 0.508 0.3048)
			(stroke
				(width 0.1)
				(type default)
			)
			(layer "B.Fab")
		)
		(pad "1" smd rect
			(at 0.5334 0 90)
			(size 0.7112 0.6096)
			(layers "B.Cu" "B.Mask" "B.Paste")
			(net "XP3R3V_FPGA")
		)
		(pad "2" smd rect
			(at -0.5334 0 90)
			(size 0.7112 0.6096)
			(layers "B.Cu" "B.Mask" "B.Paste")
			(net "UNNAMED_8_PCA9508DPTSSOP8_I51_E")
		)
		(zone
			(layer "B.Cu")
			(hatch none 0.5)
			(connect_pads
				(clearance 0)
			)
			(min_thickness 0.25)
			(keepout
				(tracks not_allowed)
				(vias allowed)
				(pads allowed)
				(copperpour not_allowed)
				(footprints allowed)
			)
			(placement
				(enabled no)
				(sheetname "")
			)
			(fill
				(thermal_gap 0.5)
				(thermal_bridge_width 0.5)
				(island_removal_mode 0)
			)
			(polygon
				(pts
					(xy 22.4536 -61.468) (xy 23.0632 -61.468) (xy 23.0632 -61.6204) (xy 22.4536 -61.6204)
				)
			)
		)
		(zone
			(layer "B.Cu")
			(hatch none 0.5)
			(connect_pads
				(clearance 0)
			)
			(min_thickness 0.25)
			(keepout
				(tracks allowed)
				(vias not_allowed)
				(pads allowed)
				(copperpour not_allowed)
				(footprints allowed)
			)
			(placement
				(enabled no)
				(sheetname "")
			)
			(fill
				(thermal_gap 0.5)
				(thermal_bridge_width 0.5)
				(island_removal_mode 0)
			)
			(polygon
				(pts
					(xy 22.4536 -61.468) (xy 23.0632 -61.468) (xy 23.0632 -61.6204) (xy 22.4536 -61.6204)
				)
			)
		)
	)
)
